# S9S_MB_2U (Grand Teton) — schematic netlist excerpt (pin names and nets, part order shuffled) for the footprints in the layout excerpt that follows; sources: Cadence DE-HDL packaged netlist, KiCad conversion of 03242023_DA0F0TMBIJ0_F0T_Motherboard_J_brd_V01_OCP.brd

J16  SCONN288_ADR50017P087CC  SCONN288_ADR50017-P087CC IO  pkg DDR288S_1-1VXB  page 97
  VIN_BULK0  = P12V_S3_AUX_CPU0_NVDIMM
  RFU0  = TP_CHH_CPU0_DIMM2_FRU_0
  VIN_MGMT  = P3V3_AUX
  HSCL  = I3C_SPD_DDREFGH_CPU0_LVC1_SCL_7
  HSDA  = I3C_SPD_DDREFGH_CPU0_LVC1_SDA
  VSS0  = GND
  DQ0_A  = M_H_CPU0_SA_DQ<0>
  VSS1  = GND
  DQ1_A  = M_H_CPU0_SA_DQ<1>
  VSS2  = GND
  DQS0_A_T  = M_H_CPU0_SA_DQS_DP<0>
  DQS0_A_C  = M_H_CPU0_SA_DQS_DN<0>
  VSS3  = GND
  DQ4_A  = M_H_CPU0_SA_DQ<4>
  VSS4  = GND
  DQ5_A  = M_H_CPU0_SA_DQ<5>
  VSS5  = GND
  DQ8_A  = M_H_CPU0_SA_DQ<8>
  VSS6  = GND
  DQ9_A  = M_H_CPU0_SA_DQ<9>
  VSS7  = GND
  DQS1_A_T  = M_H_CPU0_SA_DQS_DP<1>
  DQS1_A_C  = M_H_CPU0_SA_DQS_DN<1>
  VSS8  = GND
  DQ12_A  = M_H_CPU0_SA_DQ<12>
  VSS9  = GND
  DQ13_A  = M_H_CPU0_SA_DQ<13>
  VSS10  = GND
  DQ16_A  = M_H_CPU0_SA_DQ<16>
  VSS11  = GND
  DQ17_A  = M_H_CPU0_SA_DQ<17>
  VSS12  = GND
  DQS2_A_T  = M_H_CPU0_SA_DQS_DP<2>
  DQS2_A_C  = M_H_CPU0_SA_DQS_DN<2>
  VSS13  = GND
  DQ20_A  = M_H_CPU0_SA_DQ<20>
  VSS14  = GND
  DQ21_A  = M_H_CPU0_SA_DQ<21>
  VSS15  = GND
  DQ24_A  = M_H_CPU0_SA_DQ<24>
  VSS16  = GND
  DQ25_A  = M_H_CPU0_SA_DQ<25>
  VSS17  = GND
  DQS3_A_T  = M_H_CPU0_SA_DQS_DP<3>
  DQS3_A_C  = M_H_CPU0_SA_DQS_DN<3>
  VSS18  = GND
  DQ28_A  = M_H_CPU0_SA_DQ<28>
  VSS19  = GND
  DQ29_A  = M_H_CPU0_SA_DQ<29>
  VSS20  = GND
  CB0_A  = M_H_CPU0_SA_CB<0>
  VSS21  = GND
  CB1_A  = M_H_CPU0_SA_CB<1>
  VSS22  = GND
  DQS4_A_T  = M_H_CPU0_SA_DQS_DP<4>
  DQS4_A_C  = M_H_CPU0_SA_DQS_DN<4>
  VSS23  = GND
  CB4_A  = M_H_CPU0_SA_CB<4>
  VSS24  = GND
  CB5_A  = M_H_CPU0_SA_CB<5>
  VSS25  = GND
  ALERT_N  = M_H_CPU0_ALERT_N
  VSS26  = GND
  CS0_A_N  = M_H_CPU0_SA_CS_N<2>
  VSS27  = GND
  CA0_A  = M_H_CPU0_SA_CA<0>
  VSS28  = GND
  CA2_A  = M_H_CPU0_SA_CA<2>
  VSS29  = GND
  CA4_A  = M_H_CPU0_SA_CA<4>
  VSS30  = GND
  CA6_A  = M_H_CPU0_SA_CA<6>
  VSS31  = GND
  PAR_A  = M_H_CPU0_SA_PAR
  VSS32  = GND
  CA0_B  = M_H_CPU0_SB_CA<0>
  VSS33  = GND
  CA2_B  = M_H_CPU0_SB_CA<2>
  VSS34  = GND
  CA4_B  = M_H_CPU0_SB_CA<4>
  VSS35  = GND
  CA6_B  = M_H_CPU0_SB_CA<6>
  VSS36  = GND
  CS0_B_N  = M_H_CPU0_SB_CS_N<2>
  VSS37  = GND
  \lbd||rsp_a_n\  = M_H_CPU0_SA_RSP<1>
  \lbs||rsp_b_n\  = M_H_CPU0_SB_RSP<1>
  VSS38  = GND
  CB4_B  = M_H_CPU0_SB_CB<4>
  VSS39  = GND
  CB5_B  = M_H_CPU0_SB_CB<5>
  VSS40  = GND
  \dqs9_b_t||tdqs9_b_t||dbi4_b_n\  = M_H_CPU0_SB_DQS_DP<9>
  \dqs9_b_c||tdqs9_b_c\  = M_H_CPU0_SB_DQS_DN<9>
  VSS41  = GND
  CB0_B  = M_H_CPU0_SB_CB<0>
  VSS42  = GND
  CB1_B  = M_H_CPU0_SB_CB<1>
  VSS43  = GND
  DQ0_B  = M_H_CPU0_SB_DQ<0>
  VSS44  = GND
  DQ1_B  = M_H_CPU0_SB_DQ<1>
  VSS45  = GND
  DQS0_B_T  = M_H_CPU0_SB_DQS_DP<0>
  DQS0_B_C  = M_H_CPU0_SB_DQS_DN<0>
  VSS46  = GND
  DQ4_B  = M_H_CPU0_SB_DQ<4>
  VSS47  = GND
  DQ5_B  = M_H_CPU0_SB_DQ<5>
  VSS48  = GND
  DQ8_B  = M_H_CPU0_SB_DQ<8>
  VSS49  = GND
  DQ9_B  = M_H_CPU0_SB_DQ<9>
  VSS50  = GND
  DQS1_B_T  = M_H_CPU0_SB_DQS_DP<1>
  DQS1_B_C  = M_H_CPU0_SB_DQS_DN<1>
  VSS51  = GND
  DQ12_B  = M_H_CPU0_SB_DQ<12>
  VSS52  = GND
  DQ13_B  = M_H_CPU0_SB_DQ<13>
  VSS53  = GND
  DQ16_B  = M_H_CPU0_SB_DQ<16>
  VSS54  = GND
  DQ17_B  = M_H_CPU0_SB_DQ<17>
  VSS55  = GND
  DQS2_B_T  = M_H_CPU0_SB_DQS_DP<2>
  DQS2_B_C  = M_H_CPU0_SB_DQS_DN<2>
  VSS56  = GND
  DQ20_B  = M_H_CPU0_SB_DQ<20>
  VSS57  = GND
  DQ21_B  = M_H_CPU0_SB_DQ<21>
  VSS58  = GND
  DQ24_B  = M_H_CPU0_SB_DQ<24>
  VSS59  = GND
  DQ25_B  = M_H_CPU0_SB_DQ<25>
  VSS60  = GND
  DQS3_B_T  = M_H_CPU0_SB_DQS_DP<3>
  DQS3_B_C  = M_H_CPU0_SB_DQS_DN<3>
  VSS61  = GND
  DQ28_B  = M_H_CPU0_SB_DQ<28>
  VSS62  = GND
  DQ29_B  = M_H_CPU0_SB_DQ<29>
  VSS63  = GND
  RFU1  = TP_CHH_CPU0_DIMM2_FRU_1
  VIN_BULK1  = P12V_S3_AUX_CPU0_NVDIMM
  VIN_BULK2  = P12V_S3_AUX_CPU0_NVDIMM
  \pwr_good||fail_n\  = PWRGD_CHH_CPU0_DIMM2
  HSA  = PD_CHH_CPU0_DIMM2_SAA
  RFU2  = TP_CHH_CPU0_DIMM2_FRU_2
  RFU3  = TP_CHH_CPU0_DIMM2_FRU_3
  VSS64  = GND
  DQ2_A  = M_H_CPU0_SA_DQ<2>
  VSS65  = GND
  DQ3_A  = M_H_CPU0_SA_DQ<3>
  VSS66  = GND
  \dqs5_a_c||tdqs5_a_c||dqs5_a_t||tdqs5_a_t\  = M_H_CPU0_SA_DQS_DN<5>
  \dqs5_a_t||tdqs5_a_t\  = M_H_CPU0_SA_DQS_DP<5>
  VSS67  = GND
  DQ6_A  = M_H_CPU0_SA_DQ<6>
  VSS68  = GND
  DQ7_A  = M_H_CPU0_SA_DQ<7>
  VSS69  = GND
  DQ10_A  = M_H_CPU0_SA_DQ<10>
  VSS70  = GND
  DQ11_A  = M_H_CPU0_SA_DQ<11>
  VSS71  = GND
  \dqs6_a_c||tdqs6_a_c||dqs6_a_t||tdqs6_a_t\  = M_H_CPU0_SA_DQS_DN<6>
  \dqs6_a_t||tdqs6_a_t\  = M_H_CPU0_SA_DQS_DP<6>
  VSS72  = GND
  DQ14_A  = M_H_CPU0_SA_DQ<14>
  VSS73  = GND
  DQ15_A  = M_H_CPU0_SA_DQ<15>
  VSS74  = GND
  DQ18_A  = M_H_CPU0_SA_DQ<18>
  VSS75  = GND
  DQ19_A  = M_H_CPU0_SA_DQ<19>
  VSS76  = GND
  \dqs7_a_c||tdqs7_a_c\  = M_H_CPU0_SA_DQS_DN<7>
  \dqs7_a_t||tdqs7_a_t\  = M_H_CPU0_SA_DQS_DP<7>
  VSS77  = GND
  DQ22_A  = M_H_CPU0_SA_DQ<22>
  VSS78  = GND
  DQ23_A  = M_H_CPU0_SA_DQ<23>
  VSS79  = GND
  DQ26_A  = M_H_CPU0_SA_DQ<26>
  VSS80  = GND
  DQ27_A  = M_H_CPU0_SA_DQ<27>
  VSS81  = GND
  \dqs8_a_c||tdqs8_a_c\  = M_H_CPU0_SA_DQS_DN<8>
  \dqs8_a_t||tdqs8_a_t\  = M_H_CPU0_SA_DQS_DP<8>
  VSS82  = GND
  DQ30_A  = M_H_CPU0_SA_DQ<30>
  VSS83  = GND
  DQ31_A  = M_H_CPU0_SA_DQ<31>
  VSS84  = GND
  CB2_A  = M_H_CPU0_SA_CB<2>
  VSS85  = GND
  CB3_A  = M_H_CPU0_SA_CB<3>
  VSS86  = GND
  \dqs9_a_c||tdqs9_a_c\  = M_H_CPU0_SA_DQS_DN<9>
  \dqs9_a_t||tdqs9_a_t\  = M_H_CPU0_SA_DQS_DP<9>
  VSS87  = GND
  CB6_A  = M_H_CPU0_SA_CB<6>
  VSS88  = GND
  CB7_A  = M_H_CPU0_SA_CB<7>
  VSS89  = GND
  RESET_N  = RST_M_GH_CPU0_FPGA_N
  VSS90  = GND
  CS1_A_N  = M_H_CPU0_SA_CS_N<3>
  VSS91  = GND
  CA1_A  = M_H_CPU0_SA_CA<1>
  VSS92  = GND
  CA3_A  = M_H_CPU0_SA_CA<3>
  VSS93  = GND
  CA5_A  = M_H_CPU0_SA_CA<5>
  VSS94  = GND
  CK_T  = M_H_CPU0_CLK_DP<1>
  CK_C  = M_H_CPU0_CLK_DN<1>
  VSS95  = GND
  RFU4  = TP_CHH_CPU0_DIMM2_FRU_4
  CA1_B  = M_H_CPU0_SB_CA<1>
  VSS96  = GND
  CA3_B  = M_H_CPU0_SB_CA<3>
  VSS97  = GND
  CA5_B  = M_H_CPU0_SB_CA<5>
  VSS98  = GND
  PAR_B  = M_H_CPU0_SB_PAR
  VSS99  = GND
  CS1_B_N  = M_H_CPU0_SB_CS_N<3>
  VSS100  = GND
  RFU5  = TP_CHH_CPU0_DIMM2_FRU_5
  RFU6  = TP_CHH_CPU0_DIMM2_FRU_6
  VSS101  = GND
  CB6_B  = M_H_CPU0_SB_CB<6>
  VSS102  = GND
  CB7_B  = M_H_CPU0_SB_CB<7>
  VSS103  = GND
  DQS4_B_C  = M_H_CPU0_SB_DQS_DN<4>
  DQS4_B_T  = M_H_CPU0_SB_DQS_DP<4>
  VSS104  = GND
  CB2_B  = M_H_CPU0_SB_CB<2>
  VSS105  = GND
  CB3_B  = M_H_CPU0_SB_CB<3>
  VSS106  = GND
  DQ2_B  = M_H_CPU0_SB_DQ<2>
  VSS107  = GND
  DQ3_B  = M_H_CPU0_SB_DQ<3>
  VSS108  = GND
  \dqs5_b_c||tdqs5_b_c\  = M_H_CPU0_SB_DQS_DN<5>
  \dqs5_b_t||tdqs5_b_t\  = M_H_CPU0_SB_DQS_DP<5>
  VSS109  = GND
  DQ6_B  = M_H_CPU0_SB_DQ<6>
  VSS110  = GND
  DQ7_B  = M_H_CPU0_SB_DQ<7>
  VSS111  = GND
  DQ10_B  = M_H_CPU0_SB_DQ<10>
  VSS112  = GND
  DQ11_B  = M_H_CPU0_SB_DQ<11>
  VSS113  = GND
  \dqs6_b_c||tdqs6_b_c\  = M_H_CPU0_SB_DQS_DN<6>
  \dqs6_b_t||tdqs6_b_t\  = M_H_CPU0_SB_DQS_DP<6>
  VSS114  = GND
  DQ14_B  = M_H_CPU0_SB_DQ<14>
  VSS115  = GND
  DQ15_B  = M_H_CPU0_SB_DQ<15>
  VSS116  = GND
  DQ18_B  = M_H_CPU0_SB_DQ<18>
  VSS117  = GND
  DQ19_B  = M_H_CPU0_SB_DQ<19>
  VSS118  = GND
  \dqs7_b_c||tdqs7_b_c\  = M_H_CPU0_SB_DQS_DN<7>
  \dqs7_b_t||tdqs7_b_t\  = M_H_CPU0_SB_DQS_DP<7>
  VSS119  = GND
  DQ22_B  = M_H_CPU0_SB_DQ<22>
  VSS120  = GND
  DQ23_B  = M_H_CPU0_SB_DQ<23>
  VSS121  = GND
  DQ26_B  = M_H_CPU0_SB_DQ<26>
  VSS122  = GND
  DQ27_B  = M_H_CPU0_SB_DQ<27>
  VSS123  = GND
  \dqs8_b_c||tdqs8_b_c\  = M_H_CPU0_SB_DQS_DN<8>
  \dqs8_b_t||tdqs8_b_t\  = M_H_CPU0_SB_DQS_DP<8>
  VSS124  = GND
  DQ30_B  = M_H_CPU0_SB_DQ<30>
  VSS125  = GND
  DQ31_B  = M_H_CPU0_SB_DQ<31>
  VSS126  = GND
  G1  = GND
  G2  = GND
  G3  = GND

(kicad_pcb
	(version 20260206)
	(generator "pcbnew")
	(generator_version "10.0")
	(general
		(thickness 1.6)
		(legacy_teardrops no)
	)
	(paper "A4")
	(title_block
		(title "03242023_DA0F0TMBIJ0_F0T_Motherboard_J_brd_V01_OCP.brd")
		(comment 1 "Grand Teton / footprint 1690 of 6105 (J16), pads 138-182 of 291")
	)
	(layers
		(0 "F.Cu" signal "TOP")
		(4 "In1.Cu" signal "GND")
		(6 "In2.Cu" signal "IN1")
		(8 "In3.Cu" signal "GND1")
		(10 "In4.Cu" signal "IN2")
		(12 "In5.Cu" signal "GND2")
		(14 "In6.Cu" signal "IN3")
		(16 "In7.Cu" signal "GND3")
		(18 "In8.Cu" signal "VCC")
		(20 "In9.Cu" signal "VCC1")
		(22 "In10.Cu" signal "GND4")
		(24 "In11.Cu" signal "IN4")
		(26 "In12.Cu" signal "GND5")
		(28 "In13.Cu" signal "IN5")
		(30 "In14.Cu" signal "GND6")
		(32 "In15.Cu" signal "IN6")
		(34 "In16.Cu" signal "GND7")
		(2 "B.Cu" signal "BOTTOM")
		(9 "F.Adhes" user "F.Adhesive")
		(11 "B.Adhes" user "B.Adhesive")
		(13 "F.Paste" user "Package Geometry/Pastemask Top")
		(15 "B.Paste" user "Package Geometry/Pastemask Bottom")
		(5 "F.SilkS" user "Ref Des/Silkscreen Top")
		(7 "B.SilkS" user "Ref Des/Silkscreen Bottom")
		(1 "F.Mask" user "Board Geometry/Soldermask Top")
		(3 "B.Mask" user "Board Geometry/Soldermask Bottom")
		(17 "Dwgs.User" user "User.Drawings")
		(19 "Cmts.User" user "User.Comments")
		(21 "Eco1.User" user "User.Eco1")
		(23 "Eco2.User" user "User.Eco2")
		(25 "Edge.Cuts" user "Board Geometry/Outline")
		(27 "Margin" user)
		(31 "F.CrtYd" user "Package Geometry/Place Bound Top")
		(29 "B.CrtYd" user "Package Geometry/Place Bound Bottom")
		(35 "F.Fab" user "Ref Des/Assembly Top")
		(33 "B.Fab" user "Ref Des/Assembly Bottom")
	)
	(footprint ""
		(layer "F.Cu")
		(at 454.066148 -258.091686)
		(property "Reference" "J16"
			(at -0.279908 -81.779872 0)
			(unlocked yes)
			(layer "F.SilkS")
			(effects
				(font
					(size 0.7874 0.5842)
					(thickness 0.1524)
				)
				(justify left)
			)
		)
		(property "Value" ""
			(at 0 0 0)
			(layer "F.Fab")
			(effects
				(font
					(size 1.27 1.27)
				)
			)
		)
		(duplicate_pad_numbers_are_jumpers no)
		(pad "138" smd rect
			(at -2.050034 58.224928 270)
			(size 0.519938 1.4986)
			(layers "F.Cu" "F.Mask" "F.Paste")
			(net "M_H_CPU0_SB_DQS_DN<3>")
		)
		(pad "139" smd rect
			(at -2.050034 59.075066 270)
			(size 0.519938 1.4986)
			(layers "F.Cu" "F.Mask" "F.Paste")
			(net "GND")
		)
		(pad "140" smd rect
			(at -2.050034 59.92495 270)
			(size 0.519938 1.4986)
			(layers "F.Cu" "F.Mask" "F.Paste")
			(net "M_H_CPU0_SB_DQ<28>")
		)
		(pad "141" smd rect
			(at -2.050034 60.775088 270)
			(size 0.519938 1.4986)
			(layers "F.Cu" "F.Mask" "F.Paste")
			(net "GND")
		)
		(pad "142" smd rect
			(at -2.050034 61.624972 270)
			(size 0.519938 1.4986)
			(layers "F.Cu" "F.Mask" "F.Paste")
			(net "M_H_CPU0_SB_DQ<29>")
		)
		(pad "143" smd rect
			(at -2.050034 62.47511 270)
			(size 0.519938 1.4986)
			(layers "F.Cu" "F.Mask" "F.Paste")
			(net "GND")
		)
		(pad "144" smd rect
			(at -2.050034 63.324994 270)
			(size 0.519938 1.4986)
			(layers "F.Cu" "F.Mask" "F.Paste")
			(net "TP_CHH_CPU0_DIMM2_FRU_1")
		)
		(pad "145" smd rect
			(at 2.050034 -63.324994 270)
			(size 0.519938 1.4986)
			(layers "F.Cu" "F.Mask" "F.Paste")
			(net "P12V_S3_AUX_CPU0_NVDIMM")
		)
		(pad "146" smd rect
			(at 2.050034 -62.47511 270)
			(size 0.519938 1.4986)
			(layers "F.Cu" "F.Mask" "F.Paste")
			(net "P12V_S3_AUX_CPU0_NVDIMM")
		)
		(pad "147" smd rect
			(at 2.050034 -61.624972 270)
			(size 0.519938 1.4986)
			(layers "F.Cu" "F.Mask" "F.Paste")
			(net "PWRGD_CHH_CPU0_DIMM2")
		)
		(pad "148" smd rect
			(at 2.050034 -60.775088 270)
			(size 0.519938 1.4986)
			(layers "F.Cu" "F.Mask" "F.Paste")
			(net "PD_CHH_CPU0_DIMM2_SAA")
		)
		(pad "149" smd rect
			(at 2.050034 -59.92495 270)
			(size 0.519938 1.4986)
			(layers "F.Cu" "F.Mask" "F.Paste")
			(net "TP_CHH_CPU0_DIMM2_FRU_2")
		)
		(pad "150" smd rect
			(at 2.050034 -59.075066 270)
			(size 0.519938 1.4986)
			(layers "F.Cu" "F.Mask" "F.Paste")
			(net "TP_CHH_CPU0_DIMM2_FRU_3")
		)
		(pad "151" smd rect
			(at 2.050034 -58.224928 270)
			(size 0.519938 1.4986)
			(layers "F.Cu" "F.Mask" "F.Paste")
			(net "GND")
		)
		(pad "152" smd rect
			(at 2.050034 -57.375044 270)
			(size 0.519938 1.4986)
			(layers "F.Cu" "F.Mask" "F.Paste")
			(net "M_H_CPU0_SA_DQ<2>")
		)
		(pad "153" smd rect
			(at 2.050034 -56.524906 270)
			(size 0.519938 1.4986)
			(layers "F.Cu" "F.Mask" "F.Paste")
			(net "GND")
		)
		(pad "154" smd rect
			(at 2.050034 -55.675022 270)
			(size 0.519938 1.4986)
			(layers "F.Cu" "F.Mask" "F.Paste")
			(net "M_H_CPU0_SA_DQ<3>")
		)
		(pad "155" smd rect
			(at 2.050034 -54.824884 270)
			(size 0.519938 1.4986)
			(layers "F.Cu" "F.Mask" "F.Paste")
			(net "GND")
		)
		(pad "156" smd rect
			(at 2.050034 -53.975 270)
			(size 0.519938 1.4986)
			(layers "F.Cu" "F.Mask" "F.Paste")
			(net "M_H_CPU0_SA_DQS_DN<5>")
		)
		(pad "157" smd rect
			(at 2.050034 -53.125116 270)
			(size 0.519938 1.4986)
			(layers "F.Cu" "F.Mask" "F.Paste")
			(net "M_H_CPU0_SA_DQS_DP<5>")
		)
		(pad "158" smd rect
			(at 2.050034 -52.274978 270)
			(size 0.519938 1.4986)
			(layers "F.Cu" "F.Mask" "F.Paste")
			(net "GND")
		)
		(pad "159" smd rect
			(at 2.050034 -51.425094 270)
			(size 0.519938 1.4986)
			(layers "F.Cu" "F.Mask" "F.Paste")
			(net "M_H_CPU0_SA_DQ<6>")
		)
		(pad "160" smd rect
			(at 2.050034 -50.574956 270)
			(size 0.519938 1.4986)
			(layers "F.Cu" "F.Mask" "F.Paste")
			(net "GND")
		)
		(pad "161" smd rect
			(at 2.050034 -49.725072 270)
			(size 0.519938 1.4986)
			(layers "F.Cu" "F.Mask" "F.Paste")
			(net "M_H_CPU0_SA_DQ<7>")
		)
		(pad "162" smd rect
			(at 2.050034 -48.874934 270)
			(size 0.519938 1.4986)
			(layers "F.Cu" "F.Mask" "F.Paste")
			(net "GND")
		)
		(pad "163" smd rect
			(at 2.050034 -48.02505 270)
			(size 0.519938 1.4986)
			(layers "F.Cu" "F.Mask" "F.Paste")
			(net "M_H_CPU0_SA_DQ<10>")
		)
		(pad "164" smd rect
			(at 2.050034 -47.174912 270)
			(size 0.519938 1.4986)
			(layers "F.Cu" "F.Mask" "F.Paste")
			(net "GND")
		)
		(pad "165" smd rect
			(at 2.050034 -46.325028 270)
			(size 0.519938 1.4986)
			(layers "F.Cu" "F.Mask" "F.Paste")
			(net "M_H_CPU0_SA_DQ<11>")
		)
		(pad "166" smd rect
			(at 2.050034 -45.47489 270)
			(size 0.519938 1.4986)
			(layers "F.Cu" "F.Mask" "F.Paste")
			(net "GND")
		)
		(pad "167" smd rect
			(at 2.050034 -44.625006 270)
			(size 0.519938 1.4986)
			(layers "F.Cu" "F.Mask" "F.Paste")
			(net "M_H_CPU0_SA_DQS_DN<6>")
		)
		(pad "168" smd rect
			(at 2.050034 -43.775122 270)
			(size 0.519938 1.4986)
			(layers "F.Cu" "F.Mask" "F.Paste")
			(net "M_H_CPU0_SA_DQS_DP<6>")
		)
		(pad "169" smd rect
			(at 2.050034 -42.924984 270)
			(size 0.519938 1.4986)
			(layers "F.Cu" "F.Mask" "F.Paste")
			(net "GND")
		)
		(pad "170" smd rect
			(at 2.050034 -42.0751 270)
			(size 0.519938 1.4986)
			(layers "F.Cu" "F.Mask" "F.Paste")
			(net "M_H_CPU0_SA_DQ<14>")
		)
		(pad "171" smd rect
			(at 2.050034 -41.224962 270)
			(size 0.519938 1.4986)
			(layers "F.Cu" "F.Mask" "F.Paste")
			(net "GND")
		)
		(pad "172" smd rect
			(at 2.050034 -40.375078 270)
			(size 0.519938 1.4986)
			(layers "F.Cu" "F.Mask" "F.Paste")
			(net "M_H_CPU0_SA_DQ<15>")
		)
		(pad "173" smd rect
			(at 2.050034 -39.52494 270)
			(size 0.519938 1.4986)
			(layers "F.Cu" "F.Mask" "F.Paste")
			(net "GND")
		)
		(pad "174" smd rect
			(at 2.050034 -38.675056 270)
			(size 0.519938 1.4986)
			(layers "F.Cu" "F.Mask" "F.Paste")
			(net "M_H_CPU0_SA_DQ<18>")
		)
		(pad "175" smd rect
			(at 2.050034 -37.824918 270)
			(size 0.519938 1.4986)
			(layers "F.Cu" "F.Mask" "F.Paste")
			(net "GND")
		)
		(pad "176" smd rect
			(at 2.050034 -36.975034 270)
			(size 0.519938 1.4986)
			(layers "F.Cu" "F.Mask" "F.Paste")
			(net "M_H_CPU0_SA_DQ<19>")
		)
		(pad "177" smd rect
			(at 2.050034 -36.124896 270)
			(size 0.519938 1.4986)
			(layers "F.Cu" "F.Mask" "F.Paste")
			(net "GND")
		)
		(pad "178" smd rect
			(at 2.050034 -35.275012 270)
			(size 0.519938 1.4986)
			(layers "F.Cu" "F.Mask" "F.Paste")
			(net "M_H_CPU0_SA_DQS_DN<7>")
		)
		(pad "179" smd rect
			(at 2.050034 -34.425128 270)
			(size 0.519938 1.4986)
			(layers "F.Cu" "F.Mask" "F.Paste")
			(net "M_H_CPU0_SA_DQS_DP<7>")
		)
		(pad "180" smd rect
			(at 2.050034 -33.57499 270)
			(size 0.519938 1.4986)
			(layers "F.Cu" "F.Mask" "F.Paste")
			(net "GND")
		)
		(pad "181" smd rect
			(at 2.050034 -32.725106 270)
			(size 0.519938 1.4986)
			(layers "F.Cu" "F.Mask" "F.Paste")
			(net "M_H_CPU0_SA_DQ<22>")
		)
		(pad "182" smd rect
			(at 2.050034 -31.874968 270)
			(size 0.519938 1.4986)
			(layers "F.Cu" "F.Mask" "F.Paste")
			(net "GND")
		)
	)
)
